(kicad_pcb
	(version 20260206)
	(generator "pcbnew")
	(generator_version "10.0")
	(general
		(thickness 1.6)
		(legacy_teardrops no)
	)
	(paper "A4")
	(title_block
		(title "12092022_DA0F0TMDCD0_F0T_Management_Board_D_brd_V3_OCP.brd")
		(comment 1 "Grand Teton / footprints 1135-1140 of 1440")
	)
	(layers
		(0 "F.Cu" signal "TOP")
		(4 "In1.Cu" signal "GND")
		(6 "In2.Cu" signal "IN1")
		(8 "In3.Cu" signal "GND1")
		(10 "In4.Cu" signal "IN2")
		(12 "In5.Cu" signal "VCC")
		(14 "In6.Cu" signal "VCC1")
		(16 "In7.Cu" signal "IN3")
		(18 "In8.Cu" signal "GND2")
		(20 "In9.Cu" signal "IN4")
		(22 "In10.Cu" signal "GND3")
		(2 "B.Cu" signal "BOTTOM")
		(9 "F.Adhes" user "F.Adhesive")
		(11 "B.Adhes" user "B.Adhesive")
		(13 "F.Paste" user "Package Geometry/Pastemask Top")
		(15 "B.Paste" user "Package Geometry/Pastemask Bottom")
		(5 "F.SilkS" user "Ref Des/Silkscreen Top")
		(7 "B.SilkS" user "Ref Des/Silkscreen Bottom")
		(1 "F.Mask" user "Board Geometry/Soldermask Top")
		(3 "B.Mask" user "Board Geometry/Soldermask Bottom")
		(17 "Dwgs.User" user "User.Drawings")
		(19 "Cmts.User" user "User.Comments")
		(21 "Eco1.User" user "User.Eco1")
		(23 "Eco2.User" user "User.Eco2")
		(25 "Edge.Cuts" user "Board Geometry/Outline")
		(27 "Margin" user)
		(31 "F.CrtYd" user "Package Geometry/Place Bound Top")
		(29 "B.CrtYd" user "Package Geometry/Place Bound Bottom")
		(35 "F.Fab" user "Ref Des/Assembly Top")
		(33 "B.Fab" user "Ref Des/Assembly Bottom")
	)
	(footprint ""
		(layer "B.Cu")
		(at 63.5762 -93.8022 90)
		(property "Reference" "R667"
			(at 0 0 90)
			(layer "B.SilkS")
			(hide yes)
			(effects
				(font
					(size 1.27 1.27)
				)
				(justify mirror)
			)
		)
		(property "Value" ""
			(at 0 0 90)
			(layer "B.Fab")
			(effects
				(font
					(size 1.27 1.27)
				)
				(justify mirror)
			)
		)
		(duplicate_pad_numbers_are_jumpers no)
		(fp_line
			(start 0.7874 -0.4064)
			(end -0.7874 -0.4064)
			(stroke
				(width 0.1524)
				(type default)
			)
			(layer "B.SilkS")
		)
		(fp_line
			(start -0.7874 -0.4064)
			(end -0.7874 0.4064)
			(stroke
				(width 0.1524)
				(type default)
			)
			(layer "B.SilkS")
		)
		(fp_line
			(start 0.7874 0.4064)
			(end 0.7874 -0.4064)
			(stroke
				(width 0.1524)
				(type default)
			)
			(layer "B.SilkS")
		)
		(fp_line
			(start -0.7874 0.4064)
			(end 0.7874 0.4064)
			(stroke
				(width 0.1524)
				(type default)
			)
			(layer "B.SilkS")
		)
		(fp_line
			(start 0.67945 -0.305054)
			(end 0.12065 -0.305054)
			(stroke
				(width 0.1)
				(type default)
			)
			(layer "B.Fab")
		)
		(fp_line
			(start 0.12065 -0.305054)
			(end 0.12065 -0.2794)
			(stroke
				(width 0.1)
				(type default)
			)
			(layer "B.Fab")
		)
		(fp_line
			(start -0.12065 -0.3048)
			(end -0.67945 -0.3048)
			(stroke
				(width 0.1)
				(type default)
			)
			(layer "B.Fab")
		)
		(fp_line
			(start -0.67945 -0.3048)
			(end -0.67945 0.3048)
			(stroke
				(width 0.1)
				(type default)
			)
			(layer "B.Fab")
		)
		(fp_line
			(start 0.12065 -0.2794)
			(end -0.12065 -0.2794)
			(stroke
				(width 0.1)
				(type default)
			)
			(layer "B.Fab")
		)
		(fp_line
			(start -0.12065 -0.2794)
			(end -0.12065 -0.3048)
			(stroke
				(width 0.1)
				(type default)
			)
			(layer "B.Fab")
		)
		(fp_line
			(start 0.12065 0.2794)
			(end 0.12065 0.3048)
			(stroke
				(width 0.1)
				(type default)
			)
			(layer "B.Fab")
		)
		(fp_line
			(start -0.120396 0.2794)
			(end 0.12065 0.2794)
			(stroke
				(width 0.1)
				(type default)
			)
			(layer "B.Fab")
		)
		(fp_line
			(start 0.67945 0.3048)
			(end 0.67945 -0.305054)
			(stroke
				(width 0.1)
				(type default)
			)
			(layer "B.Fab")
		)
		(fp_line
			(start 0.12065 0.3048)
			(end 0.67945 0.3048)
			(stroke
				(width 0.1)
				(type default)
			)
			(layer "B.Fab")
		)
		(fp_line
			(start -0.120396 0.3048)
			(end -0.120396 0.2794)
			(stroke
				(width 0.1)
				(type default)
			)
			(layer "B.Fab")
		)
		(fp_line
			(start -0.67945 0.3048)
			(end -0.120396 0.3048)
			(stroke
				(width 0.1)
				(type default)
			)
			(layer "B.Fab")
		)
		(pad "1" smd circle
			(at 0.40005 0 270)
			(size 0 0)
			(layers "B.Cu" "B.Mask" "B.Paste")
			(net "P3V3_AUX")
		)
		(pad "2" smd circle
			(at -0.40005 0 270)
			(size 0 0)
			(layers "B.Cu" "B.Mask" "B.Paste")
			(net "LED_POSTCODE_INT")
		)
	)
	(footprint ""
		(layer "B.Cu")
		(at 40.887142 -63.756794 -90)
		(property "Reference" "R195"
			(at 0 0 90)
			(layer "B.SilkS")
			(hide yes)
			(effects
				(font
					(size 1.27 1.27)
				)
				(justify mirror)
			)
		)
		(property "Value" ""
			(at 0 0 90)
			(layer "B.Fab")
			(effects
				(font
					(size 1.27 1.27)
				)
				(justify mirror)
			)
		)
		(duplicate_pad_numbers_are_jumpers no)
		(fp_line
			(start -0.7874 0.4064)
			(end 0.7874 0.4064)
			(stroke
				(width 0.1524)
				(type default)
			)
			(layer "B.SilkS")
		)
		(fp_line
			(start 0.7874 0.4064)
			(end 0.7874 -0.4064)
			(stroke
				(width 0.1524)
				(type default)
			)
			(layer "B.SilkS")
		)
		(fp_line
			(start -0.7874 -0.4064)
			(end -0.7874 0.4064)
			(stroke
				(width 0.1524)
				(type default)
			)
			(layer "B.SilkS")
		)
		(fp_line
			(start 0.7874 -0.4064)
			(end -0.7874 -0.4064)
			(stroke
				(width 0.1524)
				(type default)
			)
			(layer "B.SilkS")
		)
		(fp_line
			(start -0.67945 0.3048)
			(end -0.120396 0.3048)
			(stroke
				(width 0.1)
				(type default)
			)
			(layer "B.Fab")
		)
		(fp_line
			(start -0.120396 0.3048)
			(end -0.120396 0.2794)
			(stroke
				(width 0.1)
				(type default)
			)
			(layer "B.Fab")
		)
		(fp_line
			(start 0.12065 0.3048)
			(end 0.67945 0.3048)
			(stroke
				(width 0.1)
				(type default)
			)
			(layer "B.Fab")
		)
		(fp_line
			(start 0.67945 0.3048)
			(end 0.67945 -0.305054)
			(stroke
				(width 0.1)
				(type default)
			)
			(layer "B.Fab")
		)
		(fp_line
			(start -0.120396 0.2794)
			(end 0.12065 0.2794)
			(stroke
				(width 0.1)
				(type default)
			)
			(layer "B.Fab")
		)
		(fp_line
			(start 0.12065 0.2794)
			(end 0.12065 0.3048)
			(stroke
				(width 0.1)
				(type default)
			)
			(layer "B.Fab")
		)
		(fp_line
			(start -0.12065 -0.2794)
			(end -0.12065 -0.3048)
			(stroke
				(width 0.1)
				(type default)
			)
			(layer "B.Fab")
		)
		(fp_line
			(start 0.12065 -0.2794)
			(end -0.12065 -0.2794)
			(stroke
				(width 0.1)
				(type default)
			)
			(layer "B.Fab")
		)
		(fp_line
			(start -0.67945 -0.3048)
			(end -0.67945 0.3048)
			(stroke
				(width 0.1)
				(type default)
			)
			(layer "B.Fab")
		)
		(fp_line
			(start -0.12065 -0.3048)
			(end -0.67945 -0.3048)
			(stroke
				(width 0.1)
				(type default)
			)
			(layer "B.Fab")
		)
		(fp_line
			(start 0.12065 -0.305054)
			(end 0.12065 -0.2794)
			(stroke
				(width 0.1)
				(type default)
			)
			(layer "B.Fab")
		)
		(fp_line
			(start 0.67945 -0.305054)
			(end 0.12065 -0.305054)
			(stroke
				(width 0.1)
				(type default)
			)
			(layer "B.Fab")
		)
		(pad "1" smd circle
			(at 0.40005 0 90)
			(size 0 0)
			(layers "B.Cu" "B.Mask" "B.Paste")
			(net "P1V2_P1V0_I3C_VDDL1")
		)
		(pad "2" smd circle
			(at -0.40005 0 90)
			(size 0 0)
			(layers "B.Cu" "B.Mask" "B.Paste")
			(net "I3C1_SPD_SDA")
		)
	)
	(footprint ""
		(layer "B.Cu")
		(at 25.7048 -94.8182 -90)
		(property "Reference" "R308"
			(at 0 0 90)
			(layer "B.SilkS")
			(hide yes)
			(effects
				(font
					(size 1.27 1.27)
				)
				(justify mirror)
			)
		)
		(property "Value" ""
			(at 0 0 90)
			(layer "B.Fab")
			(effects
				(font
					(size 1.27 1.27)
				)
				(justify mirror)
			)
		)
		(duplicate_pad_numbers_are_jumpers no)
		(fp_line
			(start -0.7874 0.4064)
			(end 0.7874 0.4064)
			(stroke
				(width 0.1524)
				(type default)
			)
			(layer "B.SilkS")
		)
		(fp_line
			(start 0.7874 0.4064)
			(end 0.7874 -0.4064)
			(stroke
				(width 0.1524)
				(type default)
			)
			(layer "B.SilkS")
		)
		(fp_line
			(start -0.7874 -0.4064)
			(end -0.7874 0.4064)
			(stroke
				(width 0.1524)
				(type default)
			)
			(layer "B.SilkS")
		)
		(fp_line
			(start 0.7874 -0.4064)
			(end -0.7874 -0.4064)
			(stroke
				(width 0.1524)
				(type default)
			)
			(layer "B.SilkS")
		)
		(fp_line
			(start -0.67945 0.3048)
			(end -0.120396 0.3048)
			(stroke
				(width 0.1)
				(type default)
			)
			(layer "B.Fab")
		)
		(fp_line
			(start -0.120396 0.3048)
			(end -0.120396 0.2794)
			(stroke
				(width 0.1)
				(type default)
			)
			(layer "B.Fab")
		)
		(fp_line
			(start 0.12065 0.3048)
			(end 0.67945 0.3048)
			(stroke
				(width 0.1)
				(type default)
			)
			(layer "B.Fab")
		)
		(fp_line
			(start 0.67945 0.3048)
			(end 0.67945 -0.305054)
			(stroke
				(width 0.1)
				(type default)
			)
			(layer "B.Fab")
		)
		(fp_line
			(start -0.120396 0.2794)
			(end 0.12065 0.2794)
			(stroke
				(width 0.1)
				(type default)
			)
			(layer "B.Fab")
		)
		(fp_line
			(start 0.12065 0.2794)
			(end 0.12065 0.3048)
			(stroke
				(width 0.1)
				(type default)
			)
			(layer "B.Fab")
		)
		(fp_line
			(start -0.12065 -0.2794)
			(end -0.12065 -0.3048)
			(stroke
				(width 0.1)
				(type default)
			)
			(layer "B.Fab")
		)
		(fp_line
			(start 0.12065 -0.2794)
			(end -0.12065 -0.2794)
			(stroke
				(width 0.1)
				(type default)
			)
			(layer "B.Fab")
		)
		(fp_line
			(start -0.67945 -0.3048)
			(end -0.67945 0.3048)
			(stroke
				(width 0.1)
				(type default)
			)
			(layer "B.Fab")
		)
		(fp_line
			(start -0.12065 -0.3048)
			(end -0.67945 -0.3048)
			(stroke
				(width 0.1)
				(type default)
			)
			(layer "B.Fab")
		)
		(fp_line
			(start 0.12065 -0.305054)
			(end 0.12065 -0.2794)
			(stroke
				(width 0.1)
				(type default)
			)
			(layer "B.Fab")
		)
		(fp_line
			(start 0.67945 -0.305054)
			(end 0.12065 -0.305054)
			(stroke
				(width 0.1)
				(type default)
			)
			(layer "B.Fab")
		)
		(pad "1" smd circle
			(at 0.40005 0 90)
			(size 0 0)
			(layers "B.Cu" "B.Mask" "B.Paste")
			(net "P3V3_AUX")
		)
		(pad "2" smd circle
			(at -0.40005 0 90)
			(size 0 0)
			(layers "B.Cu" "B.Mask" "B.Paste")
			(net "VCCIO3")
		)
	)
	(footprint ""
		(layer "B.Cu")
		(at 31.7754 -20.5232 90)
		(property "Reference" "FS1"
			(at -4.9022 -1.06807 270)
			(unlocked yes)
			(layer "B.SilkS")
			(effects
				(font
					(size 0.7874 0.5842)
					(thickness 0.1524)
				)
				(justify left mirror)
			)
		)
		(property "Value" ""
			(at 0 0 90)
			(layer "B.Fab")
			(effects
				(font
					(size 1.27 1.27)
				)
				(justify mirror)
			)
		)
		(duplicate_pad_numbers_are_jumpers no)
		(fp_line
			(start 2.100326 -1.100074)
			(end -2.100326 -1.100074)
			(stroke
				(width 0.1524)
				(type default)
			)
			(layer "B.SilkS")
		)
		(fp_line
			(start -2.100326 -1.100074)
			(end -2.100326 1.100074)
			(stroke
				(width 0.1524)
				(type default)
			)
			(layer "B.SilkS")
		)
		(fp_line
			(start 2.100326 1.100074)
			(end 2.100326 -1.100074)
			(stroke
				(width 0.1524)
				(type default)
			)
			(layer "B.SilkS")
		)
		(fp_line
			(start -2.100326 1.100074)
			(end 2.100326 1.100074)
			(stroke
				(width 0.1524)
				(type default)
			)
			(layer "B.SilkS")
		)
		(fp_line
			(start 1.778 -1.100074)
			(end 1.778 -0.9652)
			(stroke
				(width 0.1)
				(type default)
			)
			(layer "B.Fab")
		)
		(fp_line
			(start -1.778 -1.100074)
			(end 1.778 -1.100074)
			(stroke
				(width 0.1)
				(type default)
			)
			(layer "B.Fab")
		)
		(fp_line
			(start 2.011426 -0.9652)
			(end 2.011426 0.9652)
			(stroke
				(width 0.1)
				(type default)
			)
			(layer "B.Fab")
		)
		(fp_line
			(start 2.0066 -0.9652)
			(end 2.011426 -0.9652)
			(stroke
				(width 0.1)
				(type default)
			)
			(layer "B.Fab")
		)
		(fp_line
			(start 1.778 -0.9652)
			(end 2.0066 -0.9652)
			(stroke
				(width 0.1)
				(type default)
			)
			(layer "B.Fab")
		)
		(fp_line
			(start -1.778 -0.9652)
			(end -1.778 -1.100074)
			(stroke
				(width 0.1)
				(type default)
			)
			(layer "B.Fab")
		)
		(fp_line
			(start -2.0066 -0.9652)
			(end -1.778 -0.9652)
			(stroke
				(width 0.1)
				(type default)
			)
			(layer "B.Fab")
		)
		(fp_line
			(start -2.010918 -0.9652)
			(end -2.0066 -0.9652)
			(stroke
				(width 0.1)
				(type default)
			)
			(layer "B.Fab")
		)
		(fp_line
			(start 2.011426 0.9652)
			(end 2.0066 0.9652)
			(stroke
				(width 0.1)
				(type default)
			)
			(layer "B.Fab")
		)
		(fp_line
			(start 2.0066 0.9652)
			(end 1.778 0.9652)
			(stroke
				(width 0.1)
				(type default)
			)
			(layer "B.Fab")
		)
		(fp_line
			(start 1.778 0.9652)
			(end 1.778 1.100074)
			(stroke
				(width 0.1)
				(type default)
			)
			(layer "B.Fab")
		)
		(fp_line
			(start -1.778 0.9652)
			(end -2.0066 0.9652)
			(stroke
				(width 0.1)
				(type default)
			)
			(layer "B.Fab")
		)
		(fp_line
			(start -2.0066 0.9652)
			(end -2.010918 0.9652)
			(stroke
				(width 0.1)
				(type default)
			)
			(layer "B.Fab")
		)
		(fp_line
			(start -2.010918 0.9652)
			(end -2.010918 -0.9652)
			(stroke
				(width 0.1)
				(type default)
			)
			(layer "B.Fab")
		)
		(fp_line
			(start 1.778 1.100074)
			(end -1.778 1.100074)
			(stroke
				(width 0.1)
				(type default)
			)
			(layer "B.Fab")
		)
		(fp_line
			(start -1.778 1.100074)
			(end -1.778 0.9652)
			(stroke
				(width 0.1)
				(type default)
			)
			(layer "B.Fab")
		)
		(pad "1" smd rect
			(at 1.450086 0 270)
			(size 1.016 1.8034)
			(layers "B.Cu" "B.Mask" "B.Paste")
			(net "CRT_VCC5_2_D")
		)
		(pad "2" smd rect
			(at -1.450086 0 270)
			(size 1.016 1.8034)
			(layers "B.Cu" "B.Mask" "B.Paste")
			(net "CRT_VCC5_2_FUSE")
		)
	)
	(footprint ""
		(layer "B.Cu")
		(at 44.193968 -65.743074 -90)
		(property "Reference" "R190"
			(at 0 0 90)
			(layer "B.SilkS")
			(hide yes)
			(effects
				(font
					(size 1.27 1.27)
				)
				(justify mirror)
			)
		)
		(property "Value" ""
			(at 0 0 90)
			(layer "B.Fab")
			(effects
				(font
					(size 1.27 1.27)
				)
				(justify mirror)
			)
		)
		(duplicate_pad_numbers_are_jumpers no)
		(fp_line
			(start -0.7874 0.4064)
			(end 0.7874 0.4064)
			(stroke
				(width 0.1524)
				(type default)
			)
			(layer "B.SilkS")
		)
		(fp_line
			(start 0.7874 0.4064)
			(end 0.7874 -0.4064)
			(stroke
				(width 0.1524)
				(type default)
			)
			(layer "B.SilkS")
		)
		(fp_line
			(start -0.7874 -0.4064)
			(end -0.7874 0.4064)
			(stroke
				(width 0.1524)
				(type default)
			)
			(layer "B.SilkS")
		)
		(fp_line
			(start 0.7874 -0.4064)
			(end -0.7874 -0.4064)
			(stroke
				(width 0.1524)
				(type default)
			)
			(layer "B.SilkS")
		)
		(fp_line
			(start -0.67945 0.3048)
			(end -0.120396 0.3048)
			(stroke
				(width 0.1)
				(type default)
			)
			(layer "B.Fab")
		)
		(fp_line
			(start -0.120396 0.3048)
			(end -0.120396 0.2794)
			(stroke
				(width 0.1)
				(type default)
			)
			(layer "B.Fab")
		)
		(fp_line
			(start 0.12065 0.3048)
			(end 0.67945 0.3048)
			(stroke
				(width 0.1)
				(type default)
			)
			(layer "B.Fab")
		)
		(fp_line
			(start 0.67945 0.3048)
			(end 0.67945 -0.305054)
			(stroke
				(width 0.1)
				(type default)
			)
			(layer "B.Fab")
		)
		(fp_line
			(start -0.120396 0.2794)
			(end 0.12065 0.2794)
			(stroke
				(width 0.1)
				(type default)
			)
			(layer "B.Fab")
		)
		(fp_line
			(start 0.12065 0.2794)
			(end 0.12065 0.3048)
			(stroke
				(width 0.1)
				(type default)
			)
			(layer "B.Fab")
		)
		(fp_line
			(start -0.12065 -0.2794)
			(end -0.12065 -0.3048)
			(stroke
				(width 0.1)
				(type default)
			)
			(layer "B.Fab")
		)
		(fp_line
			(start 0.12065 -0.2794)
			(end -0.12065 -0.2794)
			(stroke
				(width 0.1)
				(type default)
			)
			(layer "B.Fab")
		)
		(fp_line
			(start -0.67945 -0.3048)
			(end -0.67945 0.3048)
			(stroke
				(width 0.1)
				(type default)
			)
			(layer "B.Fab")
		)
		(fp_line
			(start -0.12065 -0.3048)
			(end -0.67945 -0.3048)
			(stroke
				(width 0.1)
				(type default)
			)
			(layer "B.Fab")
		)
		(fp_line
			(start 0.12065 -0.305054)
			(end 0.12065 -0.2794)
			(stroke
				(width 0.1)
				(type default)
			)
			(layer "B.Fab")
		)
		(fp_line
			(start 0.67945 -0.305054)
			(end 0.12065 -0.305054)
			(stroke
				(width 0.1)
				(type default)
			)
			(layer "B.Fab")
		)
		(pad "1" smd circle
			(at 0.40005 0 90)
			(size 0 0)
			(layers "B.Cu" "B.Mask" "B.Paste")
			(net "P1V2_P1V0_I3C_VDDL1")
		)
		(pad "2" smd circle
			(at -0.40005 0 90)
			(size 0 0)
			(layers "B.Cu" "B.Mask" "B.Paste")
			(net "I3C2_SPD_SCL")
		)
	)
	(footprint ""
		(layer "B.Cu")
		(at 34.0106 -21.4122)
		(property "Reference" "R92"
			(at 0 0 0)
			(layer "B.SilkS")
			(hide yes)
			(effects
				(font
					(size 1.27 1.27)
				)
				(justify mirror)
			)
		)
		(property "Value" ""
			(at 0 0 0)
			(layer "B.Fab")
			(effects
				(font
					(size 1.27 1.27)
				)
				(justify mirror)
			)
		)
		(duplicate_pad_numbers_are_jumpers no)
		(fp_line
			(start -0.7874 -0.4064)
			(end -0.7874 0.4064)
			(stroke
				(width 0.1524)
				(type default)
			)
			(layer "B.SilkS")
		)
		(fp_line
			(start -0.7874 0.4064)
			(end 0.7874 0.4064)
			(stroke
				(width 0.1524)
				(type default)
			)
			(layer "B.SilkS")
		)
		(fp_line
			(start 0.7874 -0.4064)
			(end -0.7874 -0.4064)
			(stroke
				(width 0.1524)
				(type default)
			)
			(layer "B.SilkS")
		)
		(fp_line
			(start 0.7874 0.4064)
			(end 0.7874 -0.4064)
			(stroke
				(width 0.1524)
				(type default)
			)
			(layer "B.SilkS")
		)
		(fp_line
			(start -0.67945 -0.3048)
			(end -0.67945 0.3048)
			(stroke
				(width 0.1)
				(type default)
			)
			(layer "B.Fab")
		)
		(fp_line
			(start -0.67945 0.3048)
			(end -0.120396 0.3048)
			(stroke
				(width 0.1)
				(type default)
			)
			(layer "B.Fab")
		)
		(fp_line
			(start -0.12065 -0.3048)
			(end -0.67945 -0.3048)
			(stroke
				(width 0.1)
				(type default)
			)
			(layer "B.Fab")
		)
		(fp_line
			(start -0.12065 -0.2794)
			(end -0.12065 -0.3048)
			(stroke
				(width 0.1)
				(type default)
			)
			(layer "B.Fab")
		)
		(fp_line
			(start -0.120396 0.2794)
			(end 0.12065 0.2794)
			(stroke
				(width 0.1)
				(type default)
			)
			(layer "B.Fab")
		)
		(fp_line
			(start -0.120396 0.3048)
			(end -0.120396 0.2794)
			(stroke
				(width 0.1)
				(type default)
			)
			(layer "B.Fab")
		)
		(fp_line
			(start 0.12065 -0.305054)
			(end 0.12065 -0.2794)
			(stroke
				(width 0.1)
				(type default)
			)
			(layer "B.Fab")
		)
		(fp_line
			(start 0.12065 -0.2794)
			(end -0.12065 -0.2794)
			(stroke
				(width 0.1)
				(type default)
			)
			(layer "B.Fab")
		)
		(fp_line
			(start 0.12065 0.2794)
			(end 0.12065 0.3048)
			(stroke
				(width 0.1)
				(type default)
			)
			(layer "B.Fab")
		)
		(fp_line
			(start 0.12065 0.3048)
			(end 0.67945 0.3048)
			(stroke
				(width 0.1)
				(type default)
			)
			(layer "B.Fab")
		)
		(fp_line
			(start 0.67945 -0.305054)
			(end 0.12065 -0.305054)
			(stroke
				(width 0.1)
				(type default)
			)
			(layer "B.Fab")
		)
		(fp_line
			(start 0.67945 0.3048)
			(end 0.67945 -0.305054)
			(stroke
				(width 0.1)
				(type default)
			)
			(layer "B.Fab")
		)
		(pad "1" smd circle
			(at 0.40005 0 180)
			(size 0 0)
			(layers "B.Cu" "B.Mask" "B.Paste")
			(net "CRT_VCC5")
		)
		(pad "2" smd circle
			(at -0.40005 0 180)
			(size 0 0)
			(layers "B.Cu" "B.Mask" "B.Paste")
			(net "V_BMC_LS_DDC_SCL")
		)
	)
)
